# T6G (Grand Teton) — schematic netlist excerpt (pin names and nets, part order shuffled) for the footprints in the layout excerpt that follows; sources: Cadence DE-HDL packaged netlist, KiCad conversion of 04192023_DAF0TMB3IC0_F0TG_MB_C_brd_V02_OCP.brd

R2528  Q_RES  100K 1% CHIP  pkg 0402LF  page 242 : A = P12V_AUX ; B = FM_P12V_HSC_EN_N
R8350  Q_RES  0 5% CHIP  pkg 0402LF  page 55 : A = CLK_100M_CPU1_CLK13_R_DP ; B = CLK_100M_CPU1_CLK13_DP

(kicad_pcb
	(version 20260206)
	(generator "pcbnew")
	(generator_version "10.0")
	(general
		(thickness 1.6)
		(legacy_teardrops no)
	)
	(paper "A4")
	(title_block
		(title "04192023_DAF0TMB3IC0_F0TG_MB_C_brd_V02_OCP.brd")
		(comment 1 "Grand Teton / footprints 2015-2016 of 8354")
	)
	(layers
		(0 "F.Cu" signal "TOP")
		(4 "In1.Cu" signal "GND")
		(6 "In2.Cu" signal "IN1")
		(8 "In3.Cu" signal "GND1")
		(10 "In4.Cu" signal "IN2")
		(12 "In5.Cu" signal "GND2")
		(14 "In6.Cu" signal "IN3")
		(16 "In7.Cu" signal "GND3")
		(18 "In8.Cu" signal "VCC")
		(20 "In9.Cu" signal "VCC1")
		(22 "In10.Cu" signal "GND4")
		(24 "In11.Cu" signal "IN4")
		(26 "In12.Cu" signal "GND5")
		(28 "In13.Cu" signal "IN5")
		(30 "In14.Cu" signal "GND6")
		(32 "In15.Cu" signal "IN6")
		(34 "In16.Cu" signal "GND7")
		(2 "B.Cu" signal "BOTTOM")
		(9 "F.Adhes" user "F.Adhesive")
		(11 "B.Adhes" user "B.Adhesive")
		(13 "F.Paste" user "Package Geometry/Pastemask Top")
		(15 "B.Paste" user "Package Geometry/Pastemask Bottom")
		(5 "F.SilkS" user "Ref Des/Silkscreen Top")
		(7 "B.SilkS" user "Ref Des/Silkscreen Bottom")
		(1 "F.Mask" user "Board Geometry/Soldermask Top")
		(3 "B.Mask" user "Board Geometry/Soldermask Bottom")
		(17 "Dwgs.User" user "User.Drawings")
		(19 "Cmts.User" user "User.Comments")
		(21 "Eco1.User" user "User.Eco1")
		(23 "Eco2.User" user "User.Eco2")
		(25 "Edge.Cuts" user "Board Geometry/Outline")
		(27 "Margin" user)
		(31 "F.CrtYd" user "Package Geometry/Place Bound Top")
		(29 "B.CrtYd" user "Package Geometry/Place Bound Bottom")
		(35 "F.Fab" user "Ref Des/Assembly Top")
		(33 "B.Fab" user "Ref Des/Assembly Bottom")
	)
	(footprint ""
		(layer "F.Cu")
		(at 205.665832 -137.527792)
		(property "Reference" "R2528"
			(at 0 0 0)
			(layer "F.SilkS")
			(hide yes)
			(effects
				(font
					(size 1.27 1.27)
				)
			)
		)
		(property "Value" ""
			(at 0 0 0)
			(layer "F.Fab")
			(effects
				(font
					(size 1.27 1.27)
				)
			)
		)
		(duplicate_pad_numbers_are_jumpers no)
		(fp_line
			(start -0.7874 -0.4064)
			(end 0.7874 -0.4064)
			(stroke
				(width 0.1524)
				(type default)
			)
			(layer "F.SilkS")
		)
		(fp_line
			(start -0.7874 0.4064)
			(end -0.7874 -0.4064)
			(stroke
				(width 0.1524)
				(type default)
			)
			(layer "F.SilkS")
		)
		(fp_line
			(start 0.7874 -0.4064)
			(end 0.7874 0.4064)
			(stroke
				(width 0.1524)
				(type default)
			)
			(layer "F.SilkS")
		)
		(fp_line
			(start 0.7874 0.4064)
			(end -0.7874 0.4064)
			(stroke
				(width 0.1524)
				(type default)
			)
			(layer "F.SilkS")
		)
		(fp_line
			(start -0.67945 -0.305054)
			(end -0.12065 -0.305054)
			(stroke
				(width 0.1)
				(type default)
			)
			(layer "F.Fab")
		)
		(fp_line
			(start -0.67945 0.3048)
			(end -0.67945 -0.305054)
			(stroke
				(width 0.1)
				(type default)
			)
			(layer "F.Fab")
		)
		(fp_line
			(start -0.12065 -0.305054)
			(end -0.12065 -0.2794)
			(stroke
				(width 0.1)
				(type default)
			)
			(layer "F.Fab")
		)
		(fp_line
			(start -0.12065 -0.2794)
			(end 0.12065 -0.2794)
			(stroke
				(width 0.1)
				(type default)
			)
			(layer "F.Fab")
		)
		(fp_line
			(start -0.12065 0.2794)
			(end -0.12065 0.3048)
			(stroke
				(width 0.1)
				(type default)
			)
			(layer "F.Fab")
		)
		(fp_line
			(start -0.12065 0.3048)
			(end -0.67945 0.3048)
			(stroke
				(width 0.1)
				(type default)
			)
			(layer "F.Fab")
		)
		(fp_line
			(start 0.120396 0.2794)
			(end -0.12065 0.2794)
			(stroke
				(width 0.1)
				(type default)
			)
			(layer "F.Fab")
		)
		(fp_line
			(start 0.120396 0.3048)
			(end 0.120396 0.2794)
			(stroke
				(width 0.1)
				(type default)
			)
			(layer "F.Fab")
		)
		(fp_line
			(start 0.12065 -0.3048)
			(end 0.67945 -0.3048)
			(stroke
				(width 0.1)
				(type default)
			)
			(layer "F.Fab")
		)
		(fp_line
			(start 0.12065 -0.2794)
			(end 0.12065 -0.3048)
			(stroke
				(width 0.1)
				(type default)
			)
			(layer "F.Fab")
		)
		(fp_line
			(start 0.67945 -0.3048)
			(end 0.67945 0.3048)
			(stroke
				(width 0.1)
				(type default)
			)
			(layer "F.Fab")
		)
		(fp_line
			(start 0.67945 0.3048)
			(end 0.120396 0.3048)
			(stroke
				(width 0.1)
				(type default)
			)
			(layer "F.Fab")
		)
		(pad "1" smd circle
			(at -0.40005 0)
			(size 0 0)
			(layers "F.Cu" "F.Mask" "F.Paste")
			(net "P12V_AUX")
		)
		(pad "2" smd circle
			(at 0.40005 0)
			(size 0 0)
			(layers "F.Cu" "F.Mask" "F.Paste")
			(net "FM_P12V_HSC_EN_N")
		)
	)
	(footprint ""
		(layer "F.Cu")
		(at 121.539 -321.691 90)
		(property "Reference" "R8350"
			(at 0 0 90)
			(layer "F.SilkS")
			(hide yes)
			(effects
				(font
					(size 1.27 1.27)
				)
			)
		)
		(property "Value" ""
			(at 0 0 90)
			(layer "F.Fab")
			(effects
				(font
					(size 1.27 1.27)
				)
			)
		)
		(duplicate_pad_numbers_are_jumpers no)
		(fp_line
			(start -0.381 -0.4064)
			(end 0.4064 -0.4064)
			(stroke
				(width 0.1524)
				(type default)
			)
			(layer "F.SilkS")
		)
		(fp_line
			(start 0.7874 0)
			(end 0.7874 0.4064)
			(stroke
				(width 0.1524)
				(type default)
			)
			(layer "F.SilkS")
		)
		(fp_line
			(start 0.7874 0.4064)
			(end -0.7874 0.4064)
			(stroke
				(width 0.1524)
				(type default)
			)
			(layer "F.SilkS")
		)
		(fp_line
			(start -0.7874 0.4064)
			(end -0.7874 -0.0254)
			(stroke
				(width 0.1524)
				(type default)
			)
			(layer "F.SilkS")
		)
		(fp_line
			(start -0.12065 -0.305054)
			(end -0.12065 -0.2794)
			(stroke
				(width 0.1)
				(type default)
			)
			(layer "F.Fab")
		)
		(fp_line
			(start -0.67945 -0.305054)
			(end -0.12065 -0.305054)
			(stroke
				(width 0.1)
				(type default)
			)
			(layer "F.Fab")
		)
		(fp_line
			(start 0.67945 -0.3048)
			(end 0.67945 0.3048)
			(stroke
				(width 0.1)
				(type default)
			)
			(layer "F.Fab")
		)
		(fp_line
			(start 0.12065 -0.3048)
			(end 0.67945 -0.3048)
			(stroke
				(width 0.1)
				(type default)
			)
			(layer "F.Fab")
		)
		(fp_line
			(start 0.12065 -0.2794)
			(end 0.12065 -0.3048)
			(stroke
				(width 0.1)
				(type default)
			)
			(layer "F.Fab")
		)
		(fp_line
			(start -0.12065 -0.2794)
			(end 0.12065 -0.2794)
			(stroke
				(width 0.1)
				(type default)
			)
			(layer "F.Fab")
		)
		(fp_line
			(start 0.120396 0.2794)
			(end -0.12065 0.2794)
			(stroke
				(width 0.1)
				(type default)
			)
			(layer "F.Fab")
		)
		(fp_line
			(start -0.12065 0.2794)
			(end -0.12065 0.3048)
			(stroke
				(width 0.1)
				(type default)
			)
			(layer "F.Fab")
		)
		(fp_line
			(start 0.67945 0.3048)
			(end 0.120396 0.3048)
			(stroke
				(width 0.1)
				(type default)
			)
			(layer "F.Fab")
		)
		(fp_line
			(start 0.120396 0.3048)
			(end 0.120396 0.2794)
			(stroke
				(width 0.1)
				(type default)
			)
			(layer "F.Fab")
		)
		(fp_line
			(start -0.12065 0.3048)
			(end -0.67945 0.3048)
			(stroke
				(width 0.1)
				(type default)
			)
			(layer "F.Fab")
		)
		(fp_line
			(start -0.67945 0.3048)
			(end -0.67945 -0.305054)
			(stroke
				(width 0.1)
				(type default)
			)
			(layer "F.Fab")
		)
		(pad "1" smd circle
			(at -0.40005 0 90)
			(size 0 0)
			(layers "F.Cu" "F.Mask" "F.Paste")
			(net "CLK_100M_CPU1_CLK13_R_DP")
		)
		(pad "2" smd circle
			(at 0.40005 0 90)
			(size 0 0)
			(layers "F.Cu" "F.Mask" "F.Paste")
			(net "CLK_100M_CPU1_CLK13_DP")
		)
	)
)
